# T6G (Grand Teton) — schematic netlist excerpt (pin names and nets, part order shuffled) for the footprints in the layout excerpt that follows; sources: Cadence DE-HDL packaged netlist, KiCad conversion of 04192023_DAF0TMB3IC0_F0TG_MB_C_brd_V02_OCP.brd

C1524  Q_CAP_DIFFBUS  DIFF BUS_0.22UF 6.3V 20% X6S  pkg C0201  page 67 : \1\ = P5E_CPU1_P3_TX_C_DN<11> ; \2\ = P5E_CPU1_P3_TX_DN<11>
PC258_C0P1_1  Q_CAP  2.2UF 10V 10% X6S  pkg C0402  page 211 : A = PVDDCR_CPU0_P1_PVCC ; B = GND
R5052  Q_RES  0 5% CHIP  pkg 0402LF  page 187 : A = P3V3_RTC_AUX_R ; B = P3V3_RTC_AUX

(kicad_pcb
	(version 20260206)
	(generator "pcbnew")
	(generator_version "10.0")
	(general
		(thickness 1.6)
		(legacy_teardrops no)
	)
	(paper "A4")
	(title_block
		(title "04192023_DAF0TMB3IC0_F0TG_MB_C_brd_V02_OCP.brd")
		(comment 1 "Grand Teton / footprints 3119-3121 of 8354")
	)
	(layers
		(0 "F.Cu" signal "TOP")
		(4 "In1.Cu" signal "GND")
		(6 "In2.Cu" signal "IN1")
		(8 "In3.Cu" signal "GND1")
		(10 "In4.Cu" signal "IN2")
		(12 "In5.Cu" signal "GND2")
		(14 "In6.Cu" signal "IN3")
		(16 "In7.Cu" signal "GND3")
		(18 "In8.Cu" signal "VCC")
		(20 "In9.Cu" signal "VCC1")
		(22 "In10.Cu" signal "GND4")
		(24 "In11.Cu" signal "IN4")
		(26 "In12.Cu" signal "GND5")
		(28 "In13.Cu" signal "IN5")
		(30 "In14.Cu" signal "GND6")
		(32 "In15.Cu" signal "IN6")
		(34 "In16.Cu" signal "GND7")
		(2 "B.Cu" signal "BOTTOM")
		(9 "F.Adhes" user "F.Adhesive")
		(11 "B.Adhes" user "B.Adhesive")
		(13 "F.Paste" user "Package Geometry/Pastemask Top")
		(15 "B.Paste" user "Package Geometry/Pastemask Bottom")
		(5 "F.SilkS" user "Ref Des/Silkscreen Top")
		(7 "B.SilkS" user "Ref Des/Silkscreen Bottom")
		(1 "F.Mask" user "Board Geometry/Soldermask Top")
		(3 "B.Mask" user "Board Geometry/Soldermask Bottom")
		(17 "Dwgs.User" user "User.Drawings")
		(19 "Cmts.User" user "User.Comments")
		(21 "Eco1.User" user "User.Eco1")
		(23 "Eco2.User" user "User.Eco2")
		(25 "Edge.Cuts" user "Board Geometry/Outline")
		(27 "Margin" user)
		(31 "F.CrtYd" user "Package Geometry/Place Bound Top")
		(29 "B.CrtYd" user "Package Geometry/Place Bound Bottom")
		(35 "F.Fab" user "Ref Des/Assembly Top")
		(33 "B.Fab" user "Ref Des/Assembly Bottom")
	)
	(footprint ""
		(layer "F.Cu")
		(at 324.099174 -22.634956 -90)
		(property "Reference" "R5052"
			(at 0 0 270)
			(layer "F.SilkS")
			(hide yes)
			(effects
				(font
					(size 1.27 1.27)
				)
			)
		)
		(property "Value" ""
			(at 0 0 270)
			(layer "F.Fab")
			(effects
				(font
					(size 1.27 1.27)
				)
			)
		)
		(duplicate_pad_numbers_are_jumpers no)
		(fp_line
			(start -0.7874 0.4064)
			(end -0.7874 -0.4064)
			(stroke
				(width 0.1524)
				(type default)
			)
			(layer "F.SilkS")
		)
		(fp_line
			(start 0.7874 0.4064)
			(end -0.7874 0.4064)
			(stroke
				(width 0.1524)
				(type default)
			)
			(layer "F.SilkS")
		)
		(fp_line
			(start -0.7874 -0.4064)
			(end 0.7874 -0.4064)
			(stroke
				(width 0.1524)
				(type default)
			)
			(layer "F.SilkS")
		)
		(fp_line
			(start 0.7874 -0.4064)
			(end 0.7874 0.4064)
			(stroke
				(width 0.1524)
				(type default)
			)
			(layer "F.SilkS")
		)
		(fp_line
			(start -0.67945 0.3048)
			(end -0.67945 -0.305054)
			(stroke
				(width 0.1)
				(type default)
			)
			(layer "F.Fab")
		)
		(fp_line
			(start -0.12065 0.3048)
			(end -0.67945 0.3048)
			(stroke
				(width 0.1)
				(type default)
			)
			(layer "F.Fab")
		)
		(fp_line
			(start 0.120396 0.3048)
			(end 0.120396 0.2794)
			(stroke
				(width 0.1)
				(type default)
			)
			(layer "F.Fab")
		)
		(fp_line
			(start 0.67945 0.3048)
			(end 0.120396 0.3048)
			(stroke
				(width 0.1)
				(type default)
			)
			(layer "F.Fab")
		)
		(fp_line
			(start -0.12065 0.2794)
			(end -0.12065 0.3048)
			(stroke
				(width 0.1)
				(type default)
			)
			(layer "F.Fab")
		)
		(fp_line
			(start 0.120396 0.2794)
			(end -0.12065 0.2794)
			(stroke
				(width 0.1)
				(type default)
			)
			(layer "F.Fab")
		)
		(fp_line
			(start -0.12065 -0.2794)
			(end 0.12065 -0.2794)
			(stroke
				(width 0.1)
				(type default)
			)
			(layer "F.Fab")
		)
		(fp_line
			(start 0.12065 -0.2794)
			(end 0.12065 -0.3048)
			(stroke
				(width 0.1)
				(type default)
			)
			(layer "F.Fab")
		)
		(fp_line
			(start 0.12065 -0.3048)
			(end 0.67945 -0.3048)
			(stroke
				(width 0.1)
				(type default)
			)
			(layer "F.Fab")
		)
		(fp_line
			(start 0.67945 -0.3048)
			(end 0.67945 0.3048)
			(stroke
				(width 0.1)
				(type default)
			)
			(layer "F.Fab")
		)
		(fp_line
			(start -0.67945 -0.305054)
			(end -0.12065 -0.305054)
			(stroke
				(width 0.1)
				(type default)
			)
			(layer "F.Fab")
		)
		(fp_line
			(start -0.12065 -0.305054)
			(end -0.12065 -0.2794)
			(stroke
				(width 0.1)
				(type default)
			)
			(layer "F.Fab")
		)
		(pad "1" smd circle
			(at -0.40005 0 270)
			(size 0 0)
			(layers "F.Cu" "F.Mask" "F.Paste")
			(net "P3V3_RTC_AUX_R")
		)
		(pad "2" smd circle
			(at 0.40005 0 270)
			(size 0 0)
			(layers "F.Cu" "F.Mask" "F.Paste")
			(net "P3V3_RTC_AUX")
		)
	)
	(footprint ""
		(layer "F.Cu")
		(at 85.96757 -182.745634 90)
		(property "Reference" "PC258_C0P1_1"
			(at 0 0 90)
			(layer "F.SilkS")
			(hide yes)
			(effects
				(font
					(size 1.27 1.27)
				)
			)
		)
		(property "Value" ""
			(at 0 0 90)
			(layer "F.Fab")
			(effects
				(font
					(size 1.27 1.27)
				)
			)
		)
		(duplicate_pad_numbers_are_jumpers no)
		(fp_line
			(start 0.7874 -0.4064)
			(end 0.7874 0.4064)
			(stroke
				(width 0.1524)
				(type default)
			)
			(layer "F.SilkS")
		)
		(fp_line
			(start -0.7874 -0.4064)
			(end 0.7874 -0.4064)
			(stroke
				(width 0.1524)
				(type default)
			)
			(layer "F.SilkS")
		)
		(fp_line
			(start 0.7874 0.4064)
			(end -0.7874 0.4064)
			(stroke
				(width 0.1524)
				(type default)
			)
			(layer "F.SilkS")
		)
		(fp_line
			(start -0.7874 0.4064)
			(end -0.7874 -0.4064)
			(stroke
				(width 0.1524)
				(type default)
			)
			(layer "F.SilkS")
		)
		(fp_line
			(start -0.12065 -0.305054)
			(end -0.12065 -0.2794)
			(stroke
				(width 0.1)
				(type default)
			)
			(layer "F.Fab")
		)
		(fp_line
			(start -0.67945 -0.305054)
			(end -0.12065 -0.305054)
			(stroke
				(width 0.1)
				(type default)
			)
			(layer "F.Fab")
		)
		(fp_line
			(start 0.67945 -0.3048)
			(end 0.67945 0.3048)
			(stroke
				(width 0.1)
				(type default)
			)
			(layer "F.Fab")
		)
		(fp_line
			(start 0.12065 -0.3048)
			(end 0.67945 -0.3048)
			(stroke
				(width 0.1)
				(type default)
			)
			(layer "F.Fab")
		)
		(fp_line
			(start 0.12065 -0.2794)
			(end 0.12065 -0.3048)
			(stroke
				(width 0.1)
				(type default)
			)
			(layer "F.Fab")
		)
		(fp_line
			(start -0.12065 -0.2794)
			(end 0.12065 -0.2794)
			(stroke
				(width 0.1)
				(type default)
			)
			(layer "F.Fab")
		)
		(fp_line
			(start 0.120396 0.2794)
			(end -0.12065 0.2794)
			(stroke
				(width 0.1)
				(type default)
			)
			(layer "F.Fab")
		)
		(fp_line
			(start -0.12065 0.2794)
			(end -0.12065 0.3048)
			(stroke
				(width 0.1)
				(type default)
			)
			(layer "F.Fab")
		)
		(fp_line
			(start 0.67945 0.3048)
			(end 0.120396 0.3048)
			(stroke
				(width 0.1)
				(type default)
			)
			(layer "F.Fab")
		)
		(fp_line
			(start 0.120396 0.3048)
			(end 0.120396 0.2794)
			(stroke
				(width 0.1)
				(type default)
			)
			(layer "F.Fab")
		)
		(fp_line
			(start -0.12065 0.3048)
			(end -0.67945 0.3048)
			(stroke
				(width 0.1)
				(type default)
			)
			(layer "F.Fab")
		)
		(fp_line
			(start -0.67945 0.3048)
			(end -0.67945 -0.305054)
			(stroke
				(width 0.1)
				(type default)
			)
			(layer "F.Fab")
		)
		(pad "1" smd circle
			(at -0.40005 0 90)
			(size 0 0)
			(layers "F.Cu" "F.Mask" "F.Paste")
			(net "PVDDCR_CPU0_P1_PVCC")
		)
		(pad "2" smd circle
			(at 0.40005 0 90)
			(size 0 0)
			(layers "F.Cu" "F.Mask" "F.Paste")
			(net "GND")
		)
	)
	(footprint ""
		(layer "F.Cu")
		(at 131.425696 -373.03583 -90)
		(property "Reference" "C1524"
			(at 0 0 270)
			(layer "F.SilkS")
			(hide yes)
			(effects
				(font
					(size 1.27 1.27)
				)
			)
		)
		(property "Value" ""
			(at 0 0 270)
			(layer "F.Fab")
			(effects
				(font
					(size 1.27 1.27)
				)
			)
		)
		(duplicate_pad_numbers_are_jumpers no)
		(fp_line
			(start -0.299974 0.150114)
			(end -0.299974 -0.150114)
			(stroke
				(width 0.1)
				(type default)
			)
			(layer "F.Fab")
		)
		(fp_line
			(start 0.299974 0.150114)
			(end -0.299974 0.150114)
			(stroke
				(width 0.1)
				(type default)
			)
			(layer "F.Fab")
		)
		(fp_line
			(start -0.299974 -0.150114)
			(end 0.299974 -0.150114)
			(stroke
				(width 0.1)
				(type default)
			)
			(layer "F.Fab")
		)
		(fp_line
			(start 0.299974 -0.150114)
			(end 0.299974 0.150114)
			(stroke
				(width 0.1)
				(type default)
			)
			(layer "F.Fab")
		)
		(pad "1" smd rect
			(at -0.2667 0 270)
			(size 0.3048 0.381)
			(layers "F.Cu" "F.Mask" "F.Paste")
			(net "P5E_CPU1_P3_TX_C_DN<11>")
		)
		(pad "2" smd rect
			(at 0.2667 0 270)
			(size 0.3048 0.381)
			(layers "F.Cu" "F.Mask" "F.Paste")
			(net "P5E_CPU1_P3_TX_DN<11>")
		)
	)
)
